(kicad_pcb
	(version 20260206)
	(generator "pcbnew")
	(generator_version "10.0")
	(general
		(thickness 1.6)
		(legacy_teardrops no)
	)
	(paper "A4")
	(title_block
		(title "v1-chassis-manager — T6M_CM_d_v01_1031_1645.brd")
		(comment 1 "Open CloudServer (Microsoft) / footprints 354-363 of 2512")
	)
	(layers
		(0 "F.Cu" signal "TOP")
		(4 "In1.Cu" signal "GND1")
		(6 "In2.Cu" signal "IN1")
		(8 "In3.Cu" signal "VCC1")
		(10 "In4.Cu" signal "VCC2")
		(12 "In5.Cu" signal "GND2")
		(14 "In6.Cu" signal "IN2")
		(16 "In7.Cu" signal "IN3")
		(18 "In8.Cu" signal "GND3")
		(2 "B.Cu" signal "BOTTOM")
		(9 "F.Adhes" user "F.Adhesive")
		(11 "B.Adhes" user "B.Adhesive")
		(13 "F.Paste" user "Package Geometry/Pastemask Top")
		(15 "B.Paste" user "Package Geometry/Pastemask Bottom")
		(5 "F.SilkS" user "Ref Des/Silkscreen Top")
		(7 "B.SilkS" user "Ref Des/Silkscreen Bottom")
		(1 "F.Mask" user "Board Geometry/Soldermask Top")
		(3 "B.Mask" user "Board Geometry/Soldermask Bottom")
		(17 "Dwgs.User" user "User.Drawings")
		(19 "Cmts.User" user "User.Comments")
		(21 "Eco1.User" user "User.Eco1")
		(23 "Eco2.User" user "User.Eco2")
		(25 "Edge.Cuts" user "Board Geometry/Outline")
		(27 "Margin" user)
		(31 "F.CrtYd" user "Package Geometry/Place Bound Top")
		(29 "B.CrtYd" user "Package Geometry/Place Bound Bottom")
		(35 "F.Fab" user "Ref Des/Assembly Top")
		(33 "B.Fab" user "Ref Des/Assembly Bottom")
	)
	(footprint ""
		(layer "F.Cu")
		(at 130.108452 -158.641796 180)
		(property "Reference" "U139"
			(at 61.408818 -109.092746 90)
			(unlocked yes)
			(layer "F.SilkS")
			(effects
				(font
					(size 0.7874 0.5842)
					(thickness 0.1524)
				)
			)
		)
		(property "Value" ""
			(at 0 0 180)
			(layer "F.Fab")
			(effects
				(font
					(size 1.27 1.27)
				)
			)
		)
		(duplicate_pad_numbers_are_jumpers no)
		(fp_line
			(start 1.651 1.905)
			(end -1.651 1.905)
			(stroke
				(width 0.1524)
				(type default)
			)
			(layer "F.SilkS")
		)
		(fp_line
			(start 1.651 -1.905)
			(end 1.651 1.905)
			(stroke
				(width 0.1524)
				(type default)
			)
			(layer "F.SilkS")
		)
		(fp_line
			(start -1.651 1.905)
			(end -1.651 -1.905)
			(stroke
				(width 0.1524)
				(type default)
			)
			(layer "F.SilkS")
		)
		(fp_line
			(start -1.651 -1.905)
			(end 1.651 -1.905)
			(stroke
				(width 0.1524)
				(type default)
			)
			(layer "F.SilkS")
		)
		(fp_poly
			(pts
				(xy -1.524 0.7112) (xy -1.524 1.7526) (xy -0.508 1.7526) (xy -0.508 0.6985) (xy 0.508 0.6985) (xy 0.508 1.7526)
				(xy 1.524 1.7526) (xy 1.524 0.6985) (xy 1.524 -0.6985) (xy 0.508 -0.6985) (xy 0.508 -1.7526) (xy -0.508 -1.7526)
				(xy -0.508 -0.6985) (xy -1.524 -0.6985) (xy -1.524 0.6985)
			)
			(stroke
				(width 0)
				(type default)
			)
			(fill no)
			(layer "F.CrtYd")
		)
		(fp_text user "S"
			(at 0.499618 -0.030226 0)
			(unlocked yes)
			(layer "F.SilkS")
			(effects
				(font
					(size 0.635 0.4064)
					(thickness 0.1524)
				)
			)
		)
		(fp_text user "D"
			(at 0.172466 -2.761488 0)
			(unlocked yes)
			(layer "F.SilkS")
			(effects
				(font
					(size 0.635 0.4064)
					(thickness 0.1524)
				)
			)
		)
		(fp_text user "G"
			(at -2.52222 2.676398 0)
			(unlocked yes)
			(layer "F.SilkS")
			(effects
				(font
					(size 0.635 0.4064)
					(thickness 0.1524)
				)
			)
		)
		(pad "D" smd rect
			(at 0 -1.1176 180)
			(size 1.016 1.27)
			(layers "F.Cu" "F.Mask" "F.Paste")
			(net "I2C_PSU3_SCL")
		)
		(pad "G" smd rect
			(at -1.016 1.1176 180)
			(size 1.016 1.27)
			(layers "F.Cu" "F.Mask" "F.Paste")
			(net "PMBUS3_EN")
		)
		(pad "S" smd rect
			(at 1.016 1.1176 180)
			(size 1.016 1.27)
			(layers "F.Cu" "F.Mask" "F.Paste")
			(net "I2C_PSU3_SCL_MOS")
		)
	)
	(footprint ""
		(layer "F.Cu")
		(at 137.52576 -110.783624 -90)
		(property "Reference" "R26"
			(at 5.835904 -0.850646 90)
			(unlocked yes)
			(layer "F.SilkS")
			(effects
				(font
					(size 0.7874 0.5842)
					(thickness 0.1524)
				)
				(justify left)
			)
		)
		(property "Value" ""
			(at 0 0 270)
			(layer "F.Fab")
			(effects
				(font
					(size 1.27 1.27)
				)
			)
		)
		(duplicate_pad_numbers_are_jumpers no)
		(fp_line
			(start -0.7874 0.4064)
			(end -0.7874 -0.4064)
			(stroke
				(width 0.1524)
				(type default)
			)
			(layer "F.SilkS")
		)
		(fp_line
			(start 0.7874 0.4064)
			(end -0.7874 0.4064)
			(stroke
				(width 0.1524)
				(type default)
			)
			(layer "F.SilkS")
		)
		(fp_line
			(start -0.7874 -0.4064)
			(end 0.7874 -0.4064)
			(stroke
				(width 0.1524)
				(type default)
			)
			(layer "F.SilkS")
		)
		(fp_line
			(start 0.7874 -0.4064)
			(end 0.7874 0.4064)
			(stroke
				(width 0.1524)
				(type default)
			)
			(layer "F.SilkS")
		)
		(fp_poly
			(pts
				(xy -0.508 0.2794) (xy -0.508 0.2286) (xy -0.635 0.2286) (xy -0.635 -0.254) (xy -0.5334 -0.254)
				(xy -0.5334 -0.2794) (xy 0.5334 -0.2794) (xy 0.5334 -0.254) (xy 0.635 -0.254) (xy 0.635 0.254) (xy 0.5334 0.254)
				(xy 0.5334 0.2794)
			)
			(stroke
				(width 0)
				(type default)
			)
			(fill no)
			(layer "F.CrtYd")
		)
		(pad "1" smd rect
			(at 0.40005 0 270)
			(size 0.4572 0.508)
			(layers "F.Cu" "F.Mask" "F.Paste")
			(net "GND")
		)
		(pad "2" smd rect
			(at -0.40005 0 270)
			(size 0.4572 0.508)
			(layers "F.Cu" "F.Mask" "F.Paste")
			(net "CLK_14M_CPU_NODE1_R")
		)
	)
	(footprint ""
		(layer "F.Cu")
		(at 35.669728 -79.893922)
		(property "Reference" "R40"
			(at -4.58851 -0.106934 0)
			(unlocked yes)
			(layer "F.SilkS")
			(effects
				(font
					(size 0.7874 0.5842)
					(thickness 0.1524)
				)
				(justify left)
			)
		)
		(property "Value" ""
			(at 0 0 0)
			(layer "F.Fab")
			(effects
				(font
					(size 1.27 1.27)
				)
			)
		)
		(duplicate_pad_numbers_are_jumpers no)
		(fp_line
			(start -0.7874 -0.4064)
			(end 0.7874 -0.4064)
			(stroke
				(width 0.1524)
				(type default)
			)
			(layer "F.SilkS")
		)
		(fp_line
			(start -0.7874 0.4064)
			(end -0.7874 -0.4064)
			(stroke
				(width 0.1524)
				(type default)
			)
			(layer "F.SilkS")
		)
		(fp_line
			(start 0.7874 -0.4064)
			(end 0.7874 0.4064)
			(stroke
				(width 0.1524)
				(type default)
			)
			(layer "F.SilkS")
		)
		(fp_line
			(start 0.7874 0.4064)
			(end -0.7874 0.4064)
			(stroke
				(width 0.1524)
				(type default)
			)
			(layer "F.SilkS")
		)
		(fp_poly
			(pts
				(xy -0.508 0.2794) (xy -0.508 0.2286) (xy -0.635 0.2286) (xy -0.635 -0.254) (xy -0.5334 -0.254)
				(xy -0.5334 -0.2794) (xy 0.5334 -0.2794) (xy 0.5334 -0.254) (xy 0.635 -0.254) (xy 0.635 0.254) (xy 0.5334 0.254)
				(xy 0.5334 0.2794)
			)
			(stroke
				(width 0)
				(type default)
			)
			(fill no)
			(layer "F.CrtYd")
		)
		(pad "1" smd rect
			(at 0.40005 0)
			(size 0.4572 0.508)
			(layers "F.Cu" "F.Mask" "F.Paste")
			(net "PD_CPU_NODE1_Y2")
		)
		(pad "2" smd rect
			(at -0.40005 0)
			(size 0.4572 0.508)
			(layers "F.Cu" "F.Mask" "F.Paste")
			(net "GND")
		)
	)
	(footprint ""
		(layer "F.Cu")
		(at -74.811128 -265.390884)
		(property "Reference" "H10_NUT"
			(at -1.157732 0.435102 0)
			(unlocked yes)
			(layer "B.SilkS")
			(effects
				(font
					(size 0.7874 0.5842)
					(thickness 0.1524)
				)
				(justify left mirror)
			)
		)
		(property "Value" ""
			(at 0 0 0)
			(layer "F.Fab")
			(effects
				(font
					(size 1.27 1.27)
				)
			)
		)
		(duplicate_pad_numbers_are_jumpers no)
		(fp_poly
			(pts
				(arc
					(start 0.3302 0)
					(mid -0.3302 0)
					(end 0.3302 0)
				)
			)
			(stroke
				(width 0)
				(type default)
			)
			(fill no)
			(layer "B.CrtYd")
		)
		(pad "1" thru_hole circle
			(at 0 0)
			(size 0.508 0.508)
			(drill 0.254)
			(layers "*.Cu" "*.Mask")
			(remove_unused_layers no)
			(net "Net_218")
			(clearance 0.127)
			(thermal_gap 0.127)
			(padstack
				(mode front_inner_back)
				(layer "Inner"
					(shape circle)
					(size 0.508 0.508)
					(clearance 0.127)
				)
				(layer "B.Cu"
					(shape circle)
					(size 0.6604 0.6604)
					(clearance 0.0508)
				)
			)
		)
	)
	(footprint ""
		(layer "F.Cu")
		(at 80.527398 -138.786616)
		(property "Reference" "C838"
			(at -2.036318 3.04927 0)
			(unlocked yes)
			(layer "F.SilkS")
			(effects
				(font
					(size 0.635 0.4064)
					(thickness 0.1524)
				)
				(justify left)
			)
		)
		(property "Value" ""
			(at 0 0 0)
			(layer "F.Fab")
			(effects
				(font
					(size 1.27 1.27)
				)
			)
		)
		(duplicate_pad_numbers_are_jumpers no)
		(fp_line
			(start -1.905 -0.8636)
			(end 1.905 -0.8636)
			(stroke
				(width 0.1524)
				(type default)
			)
			(layer "F.SilkS")
		)
		(fp_line
			(start -1.905 0.8636)
			(end -1.905 -0.8636)
			(stroke
				(width 0.1524)
				(type default)
			)
			(layer "F.SilkS")
		)
		(fp_line
			(start 0 0.8382)
			(end 0 -0.8382)
			(stroke
				(width 0.1524)
				(type default)
			)
			(layer "F.SilkS")
		)
		(fp_line
			(start 1.905 -0.8636)
			(end 1.905 0.8636)
			(stroke
				(width 0.1524)
				(type default)
			)
			(layer "F.SilkS")
		)
		(fp_line
			(start 1.905 0.8636)
			(end -1.905 0.8636)
			(stroke
				(width 0.1524)
				(type default)
			)
			(layer "F.SilkS")
		)
		(fp_rect
			(start -1.524 0.7366)
			(end 1.524 -0.7366)
			(stroke
				(width 0)
				(type default)
			)
			(fill no)
			(layer "F.CrtYd")
		)
		(pad "1" smd rect
			(at 0.94996 0)
			(size 1.1176 1.3716)
			(layers "F.Cu" "F.Mask" "F.Paste")
			(net "P1V26_BMC_NODE1")
		)
		(pad "2" smd rect
			(at -0.94996 0)
			(size 1.1176 1.3716)
			(layers "F.Cu" "F.Mask" "F.Paste")
			(net "GND")
		)
	)
	(footprint ""
		(layer "F.Cu")
		(at 69.96176 -185.205624 -90)
		(property "Reference" "R953"
			(at -4.006088 0.889762 90)
			(unlocked yes)
			(layer "F.SilkS")
			(effects
				(font
					(size 0.7874 0.5842)
					(thickness 0.1524)
				)
				(justify left)
			)
		)
		(property "Value" ""
			(at 0 0 270)
			(layer "F.Fab")
			(effects
				(font
					(size 1.27 1.27)
				)
			)
		)
		(duplicate_pad_numbers_are_jumpers no)
		(fp_line
			(start -0.7874 0.4064)
			(end -0.7874 -0.4064)
			(stroke
				(width 0.1524)
				(type default)
			)
			(layer "F.SilkS")
		)
		(fp_line
			(start 0.7874 0.4064)
			(end -0.7874 0.4064)
			(stroke
				(width 0.1524)
				(type default)
			)
			(layer "F.SilkS")
		)
		(fp_line
			(start -0.7874 -0.4064)
			(end 0.7874 -0.4064)
			(stroke
				(width 0.1524)
				(type default)
			)
			(layer "F.SilkS")
		)
		(fp_line
			(start 0.7874 -0.4064)
			(end 0.7874 0.4064)
			(stroke
				(width 0.1524)
				(type default)
			)
			(layer "F.SilkS")
		)
		(fp_poly
			(pts
				(xy -0.508 0.2794) (xy -0.508 0.2286) (xy -0.635 0.2286) (xy -0.635 -0.254) (xy -0.5334 -0.254)
				(xy -0.5334 -0.2794) (xy 0.5334 -0.2794) (xy 0.5334 -0.254) (xy 0.635 -0.254) (xy 0.635 0.254) (xy 0.5334 0.254)
				(xy 0.5334 0.2794)
			)
			(stroke
				(width 0)
				(type default)
			)
			(fill no)
			(layer "F.CrtYd")
		)
		(pad "1" smd rect
			(at 0.40005 0 270)
			(size 0.4572 0.508)
			(layers "F.Cu" "F.Mask" "F.Paste")
			(net "UART_T4_NODE4_TXD")
		)
		(pad "2" smd rect
			(at -0.40005 0 270)
			(size 0.4572 0.508)
			(layers "F.Cu" "F.Mask" "F.Paste")
			(net "UART_T4_NODE4_TXD_R")
		)
	)
	(footprint ""
		(layer "F.Cu")
		(at 63.10376 -185.205624 -90)
		(property "Reference" "R934"
			(at -4.006088 0.728218 90)
			(unlocked yes)
			(layer "F.SilkS")
			(effects
				(font
					(size 0.7874 0.5842)
					(thickness 0.1524)
				)
				(justify left)
			)
		)
		(property "Value" ""
			(at 0 0 270)
			(layer "F.Fab")
			(effects
				(font
					(size 1.27 1.27)
				)
			)
		)
		(duplicate_pad_numbers_are_jumpers no)
		(fp_line
			(start -0.7874 0.4064)
			(end -0.7874 -0.4064)
			(stroke
				(width 0.1524)
				(type default)
			)
			(layer "F.SilkS")
		)
		(fp_line
			(start 0.7874 0.4064)
			(end -0.7874 0.4064)
			(stroke
				(width 0.1524)
				(type default)
			)
			(layer "F.SilkS")
		)
		(fp_line
			(start -0.7874 -0.4064)
			(end 0.7874 -0.4064)
			(stroke
				(width 0.1524)
				(type default)
			)
			(layer "F.SilkS")
		)
		(fp_line
			(start 0.7874 -0.4064)
			(end 0.7874 0.4064)
			(stroke
				(width 0.1524)
				(type default)
			)
			(layer "F.SilkS")
		)
		(fp_poly
			(pts
				(xy -0.508 0.2794) (xy -0.508 0.2286) (xy -0.635 0.2286) (xy -0.635 -0.254) (xy -0.5334 -0.254)
				(xy -0.5334 -0.2794) (xy 0.5334 -0.2794) (xy 0.5334 -0.254) (xy 0.635 -0.254) (xy 0.635 0.254) (xy 0.5334 0.254)
				(xy 0.5334 0.2794)
			)
			(stroke
				(width 0)
				(type default)
			)
			(fill no)
			(layer "F.CrtYd")
		)
		(pad "1" smd rect
			(at 0.40005 0 270)
			(size 0.4572 0.508)
			(layers "F.Cu" "F.Mask" "F.Paste")
			(net "UART_T2_NODE1_TXD")
		)
		(pad "2" smd rect
			(at -0.40005 0 270)
			(size 0.4572 0.508)
			(layers "F.Cu" "F.Mask" "F.Paste")
			(net "UART_T2_NODE1_TXD_R")
		)
	)
	(footprint ""
		(layer "F.Cu")
		(at 171.151042 -136.335008 180)
		(property "Reference" "R1053"
			(at 2.942082 9.40308 0)
			(unlocked yes)
			(layer "F.SilkS")
			(effects
				(font
					(size 0.7874 0.5842)
					(thickness 0.1524)
				)
				(justify left)
			)
		)
		(property "Value" ""
			(at 0 0 180)
			(layer "F.Fab")
			(effects
				(font
					(size 1.27 1.27)
				)
			)
		)
		(duplicate_pad_numbers_are_jumpers no)
		(fp_line
			(start 0.7874 0.4064)
			(end -0.7874 0.4064)
			(stroke
				(width 0.1524)
				(type default)
			)
			(layer "F.SilkS")
		)
		(fp_line
			(start 0.7874 -0.4064)
			(end 0.7874 0.4064)
			(stroke
				(width 0.1524)
				(type default)
			)
			(layer "F.SilkS")
		)
		(fp_line
			(start -0.7874 0.4064)
			(end -0.7874 -0.4064)
			(stroke
				(width 0.1524)
				(type default)
			)
			(layer "F.SilkS")
		)
		(fp_line
			(start -0.7874 -0.4064)
			(end 0.7874 -0.4064)
			(stroke
				(width 0.1524)
				(type default)
			)
			(layer "F.SilkS")
		)
		(fp_poly
			(pts
				(xy -0.508 0.2794) (xy -0.508 0.2286) (xy -0.635 0.2286) (xy -0.635 -0.254) (xy -0.5334 -0.254)
				(xy -0.5334 -0.2794) (xy 0.5334 -0.2794) (xy 0.5334 -0.254) (xy 0.635 -0.254) (xy 0.635 0.254) (xy 0.5334 0.254)
				(xy 0.5334 0.2794)
			)
			(stroke
				(width 0)
				(type default)
			)
			(fill no)
			(layer "F.CrtYd")
		)
		(pad "1" smd rect
			(at 0.40005 0 180)
			(size 0.4572 0.508)
			(layers "F.Cu" "F.Mask" "F.Paste")
			(net "PWR_BTN_NODE1_L")
		)
		(pad "2" smd rect
			(at -0.40005 0 180)
			(size 0.4572 0.508)
			(layers "F.Cu" "F.Mask" "F.Paste")
			(net "P3V3_STB_NODE1")
		)
	)
	(footprint ""
		(layer "F.Cu")
		(at 94.060772 -94.109032)
		(property "Reference" "R178"
			(at -0.432816 1.176782 0)
			(unlocked yes)
			(layer "F.SilkS")
			(effects
				(font
					(size 0.7874 0.5842)
					(thickness 0.1524)
				)
				(justify left)
			)
		)
		(property "Value" ""
			(at 0 0 0)
			(layer "F.Fab")
			(effects
				(font
					(size 1.27 1.27)
				)
			)
		)
		(duplicate_pad_numbers_are_jumpers no)
		(fp_line
			(start -0.7874 -0.4064)
			(end 0.7874 -0.4064)
			(stroke
				(width 0.1524)
				(type default)
			)
			(layer "F.SilkS")
		)
		(fp_line
			(start -0.7874 0.4064)
			(end -0.7874 -0.4064)
			(stroke
				(width 0.1524)
				(type default)
			)
			(layer "F.SilkS")
		)
		(fp_line
			(start 0.7874 -0.4064)
			(end 0.7874 0.4064)
			(stroke
				(width 0.1524)
				(type default)
			)
			(layer "F.SilkS")
		)
		(fp_line
			(start 0.7874 0.4064)
			(end -0.7874 0.4064)
			(stroke
				(width 0.1524)
				(type default)
			)
			(layer "F.SilkS")
		)
		(fp_poly
			(pts
				(xy -0.508 0.2794) (xy -0.508 0.2286) (xy -0.635 0.2286) (xy -0.635 -0.254) (xy -0.5334 -0.254)
				(xy -0.5334 -0.2794) (xy 0.5334 -0.2794) (xy 0.5334 -0.254) (xy 0.635 -0.254) (xy 0.635 0.254) (xy 0.5334 0.254)
				(xy 0.5334 0.2794)
			)
			(stroke
				(width 0)
				(type default)
			)
			(fill no)
			(layer "F.CrtYd")
		)
		(pad "1" smd rect
			(at 0.40005 0)
			(size 0.4572 0.508)
			(layers "F.Cu" "F.Mask" "F.Paste")
			(net "SPI_CPU_NODE1_MISO")
		)
		(pad "2" smd rect
			(at -0.40005 0)
			(size 0.4572 0.508)
			(layers "F.Cu" "F.Mask" "F.Paste")
			(net "SPI_CPU_NODE1_MISO_R")
		)
	)
	(footprint ""
		(layer "F.Cu")
		(at 130.79476 -185.205624 90)
		(property "Reference" "C734"
			(at 4.510786 1.00838 90)
			(unlocked yes)
			(layer "F.SilkS")
			(effects
				(font
					(size 0.7874 0.5842)
					(thickness 0.1524)
				)
				(justify left)
			)
		)
		(property "Value" ""
			(at 0 0 90)
			(layer "F.Fab")
			(effects
				(font
					(size 1.27 1.27)
				)
			)
		)
		(duplicate_pad_numbers_are_jumpers no)
		(fp_line
			(start 0.7874 -0.4064)
			(end 0.7874 0.4064)
			(stroke
				(width 0.1524)
				(type default)
			)
			(layer "F.SilkS")
		)
		(fp_line
			(start -0.7874 -0.4064)
			(end 0.7874 -0.4064)
			(stroke
				(width 0.1524)
				(type default)
			)
			(layer "F.SilkS")
		)
		(fp_line
			(start 0 0.381)
			(end 0 -0.381)
			(stroke
				(width 0.1524)
				(type default)
			)
			(layer "F.SilkS")
		)
		(fp_line
			(start 0.7874 0.4064)
			(end -0.7874 0.4064)
			(stroke
				(width 0.1524)
				(type default)
			)
			(layer "F.SilkS")
		)
		(fp_line
			(start -0.7874 0.4064)
			(end -0.7874 -0.4064)
			(stroke
				(width 0.1524)
				(type default)
			)
			(layer "F.SilkS")
		)
		(fp_poly
			(pts
				(xy -0.5334 0.254) (xy -0.635 0.254) (xy -0.635 0.2286) (xy -0.635 -0.254) (xy -0.5334 -0.254) (xy -0.5334 -0.2794)
				(xy 0.5334 -0.2794) (xy 0.5334 -0.254) (xy 0.635 -0.254) (xy 0.635 0.254) (xy 0.5334 0.254) (xy 0.5334 0.2794)
				(xy -0.508 0.2794) (xy -0.5334 0.2794)
			)
			(stroke
				(width 0)
				(type default)
			)
			(fill no)
			(layer "F.CrtYd")
		)
		(pad "1" smd rect
			(at 0.40005 0 90)
			(size 0.4572 0.508)
			(layers "F.Cu" "F.Mask" "F.Paste")
			(net "UART_T9_NODE3_TXD_R")
		)
		(pad "2" smd rect
			(at -0.40005 0 90)
			(size 0.4572 0.508)
			(layers "F.Cu" "F.Mask" "F.Paste")
			(net "GND")
		)
	)
)
